FILE_TYPE = CONNECTIVITY;
{Allegro Design Entry HDL 16.6-p007 (v16-6-112F) 10/10/2012}
"PAGE_NUMBER" = 216;
0"NC";
1"PVDDQ_ABC\g";
2"GND\g";
3"GND\g";
4"GND\g";
5"GND\g";
6"GND\g";
7"GND\g";
8"GND\g";
9"GND\g";
10"GND\g";
11"GND\g";
12"PVDDQ_ABC\g";
13"GND\g";
14"GND\g";
15"GND\g";
16"VR_FET_SW_P12V_STBY_PVDDQ_ABC\g";
17"GND\g";
18"VR_FET_SW_P12V_STBY_PVDDQ_ABC\g";
19"P5V_STBY\g";
20"P5V_STBY\g";
21"VR_PVDDQ_ABC_PH1_OCSET"VOLTAGE"3.6";
22"VR_PVDDQ_ABC_PH2_OCSET"VOLTAGE"3.6";
23"ISENSE_PVDDQ_ABC_PH1_IMON";
24"A_TSENSE_PVDDQ_ABC";
25"VR_PVDDQ_ABC_PH1_SW_RC";
26"VR_PVDDQ_ABC_PH1_SW";
27"ISENSE_PVDDQ_ABC_PH2_IMON";
28"A_TSENSE_PVDDQ_ABC";
29"VR_PVDDQ_ABC_AIREF1";
30"VR_PVDDQ_ABC_AIREF2";
31"TP_PVDDQ_ABC_PH1_GL_0";
32"TP_PVDDQ_ABC_PH1_GL_1";
33"VR_PVDDQ_ABC_PH1_BOOT_R";
34"VR_PVDDQ_ABC_PH1_PHASE";
35"VR_PVDDQ_ABC_PH2_SW_RC";
36"VR_PVDDQ_ABC_PH2_SW";
37"VR_PVDDQ_ABC_PH2_PHASE";
38"VR_PVDDQ_ABC_PH2_BOOT_R";
39"TP_PVDDQ_ABC_PH2_GL_1";
40"TP_PVDDQ_ABC_PH2_GL_0";
41"VR_PVDDQ_ABC_PWM2";
42"VR_PVDDQ_ABC_PH1_BOOT";
43"VR_PVDDQ_ABC_PWM1";
44"VR_PVDDQ_ABC_PH1_VCIN";
45"VR_PVDDQ_ABC_PH2_BOOT";
46"VR_PVDDQ_ABC_PH2_VCIN";
%"PVDDQ_ABC"
"1","(4350,2100)","0","mstr_symbols","I1";
;
HDL_POWER"PVDDQ_ABC"
BODY_TYPE"PLUMBING"
VOLTAGE"1.2V"
CDS_LIB"mstr_symbols";
"G\NAC"1;
%"IR354XX"
"1","(1775,2300)","0","mstr_discrete","I102";
;
CDS_SEC"1"
PART_NUMBER"H73688-001"
MATERIAL"IC"
LOCATION"EU7G2"
NO_XNET_CONNECTION"1"
VALUE"IR35411"
CDS_LOCATION"EU7G2"
SEC"1"
SEC_TYPE"SM"
PACK_TYPE"SM"
CDS_LIB"mstr_discrete";
"TOUT_FLT"
$PN"36"24;
"NC"
$PN"31"0;
"OCSET"
$PN"37"21;
"IOUT"
$PN"38"23;
"SW"
$PN"10"26;
"BOOST"
$PN"33"33;
"REFIN"
$PN"39"29;
"PWM"
$PN"34"43;
"PHASE"
$PN"32"34;
"VIN<0>"
$PN"25"18;
"VCC"
$PN"3"44;
"VIN<1>"
$PN"30"18;
"EN"
$PN"35"19;
"VDRV"
$PN"4"19;
"VOS"
$PN"1"1;
"LGND"
$PN"2"10;
"PGND<1>"
$PN"7"10;
"PGND<2>"
$PN"40"10;
"PGND<0>"
$PN"5"10;
"GL<0>"
$PN"6"31;
"GL<1>"
$PN"41"32;
%"IR354XX"
"1","(1775,-75)","0","mstr_discrete","I103";
;
CDS_SEC"1"
PART_NUMBER"H73688-001"
BOM_SS"NOPOP"
LOCATION"EU7G3"
MATERIAL"IC"
NO_XNET_CONNECTION"1"
VALUE"IR35411"
CDS_LIB"mstr_discrete"
CDS_LOCATION"EU7G3"
SEC"1"
SEC_TYPE"SM"
PACK_TYPE"SM";
"TOUT_FLT"
$PN"36"28;
"NC"
$PN"31"0;
"OCSET"
$PN"37"22;
"IOUT"
$PN"38"27;
"SW"
$PN"10"36;
"BOOST"
$PN"33"38;
"REFIN"
$PN"39"30;
"PWM"
$PN"34"41;
"PHASE"
$PN"32"37;
"VIN<0>"
$PN"25"16;
"VCC"
$PN"3"46;
"VIN<1>"
$PN"30"16;
"EN"
$PN"35"20;
"VDRV"
$PN"4"20;
"VOS"
$PN"1"12;
"LGND"
$PN"2"15;
"PGND<1>"
$PN"7"15;
"PGND<2>"
$PN"40"15;
"PGND<0>"
$PN"5"15;
"GL<0>"
$PN"6"40;
"GL<1>"
$PN"41"39;
%"RES"
"2","(4575,2450)","0","mstr_discrete","I104";
;
CDS_SEC"1"
CDS_LOCATION"R7G25"
PACK_TYPE"0402"
TOLERANCE"1%"
VALUE"68.1K"
MATERIAL"EMPTY"
WATTAGE"1/16W"
PART_NUMBER"G21796-187"
LOCATION"R7G25"
CDS_LIB"mstr_discrete"
SEC"1"
SEC_TYPE"0402";
"A"
$PN"1"21;
"B"
$PN"2"2;
%"GND"
"1","(4575,2250)","0","mstr_symbols","I105";
;
HDL_POWER"GND"
BODY_TYPE"PLUMBING"
SIZE"1B"
CDS_LIB"mstr_symbols"
VOLTAGE"0"
BOM_COST"PROC_VRD_VCCIN_CPU0"
ROOM"PVCCIN_CPU0_PWR_VR";
"A\NAC"2;
%"RES"
"2","(4675,50)","0","mstr_discrete","I106";
;
CDS_SEC"1"
CDS_LOCATION"R7G30"
PACK_TYPE"0402"
PART_NUMBER"G21796-187"
BOM_SS"NOPOP"
MATERIAL"EMPTY"
WATTAGE"1/16W"
TOLERANCE"1%"
VALUE"68.1K"
LOCATION"R7G30"
CDS_LIB"mstr_discrete"
SEC"1"
SEC_TYPE"0402";
"A"
$PN"1"22;
"B"
$PN"2"3;
%"GND"
"1","(4675,-175)","0","mstr_symbols","I107";
;
HDL_POWER"GND"
BODY_TYPE"PLUMBING"
ROOM"PVCCIN_CPU0_PWR_VR"
BOM_COST"PROC_VRD_VCCIN_CPU0"
CDS_LIB"mstr_symbols"
VOLTAGE"0"
SIZE"1B";
"A\NAC"3;
%"CAP_A"
"1","(1025,1800)","0","dev_discrete","I108";
;
CDS_SEC"1"
CDS_LOCATION"CT51"
TOLERANCE"10%"
PACK_TYPE"0402V"
MATERIAL"X7R"
VALUE"0.1UF"
VOLTAGE"16V"
LOCATION"CT51"
PART_NUMBER"A36096-030"
POP"NOPOP"
SEC_TYPE"0402V"
SEC"1"
CDS_LIB"dev_discrete"
ROOM"PVCCIN_CPU0_PWR_VR";
"B"
$PN"2"4;
"A"
$PN"1"29;
%"GND"
"1","(1025,1550)","0","mstr_symbols","I109";
;
HDL_POWER"GND"
BODY_TYPE"PLUMBING"
CDS_LIB"mstr_symbols"
VOLTAGE"0"
SIZE"1B"
BOM_COST"PROC_VRD_VCCIN_CPU0"
ROOM"PVCCIN_CPU0_PWR_VR";
"A\NAC"4;
%"CAP_A"
"1","(1125,-950)","0","dev_discrete","I111";
;
CDS_SEC"1"
CDS_LOCATION"CT52"
LOCATION"CT52"
MATERIAL"X7R"
PACK_TYPE"0402V"
PART_NUMBER"A36096-030"
POP"NOPOP"
BOM_SS"NOPOP"
VOLTAGE"16V"
TOLERANCE"10%"
VALUE"0.1UF"
SEC"1"
SEC_TYPE"0402V"
ROOM"PVCCIN_CPU0_PWR_VR"
CDS_LIB"dev_discrete";
"B"
$PN"2"5;
"A"
$PN"1"30;
%"GND"
"1","(1125,-1150)","0","mstr_symbols","I112";
;
HDL_POWER"GND"
BODY_TYPE"PLUMBING"
ROOM"PVCCIN_CPU0_PWR_VR"
BOM_COST"PROC_VRD_VCCIN_CPU0"
SIZE"1B"
VOLTAGE"0"
CDS_LIB"mstr_symbols";
"A\NAC"5;
%"GND"
"1","(2900,1275)","0","mstr_symbols","I115";
;
ROOM"PVCCIN_CPU0_PWR_VR"
BOM_COST"PROC_VRD_VCCIN_CPU0"
VOLTAGE"0"
SIZE"1B"
CDS_LIB"mstr_symbols"
BODY_TYPE"PLUMBING"
HDL_POWER"GND";
"A\NAC"6;
%"GND"
"1","(3000,2175)","0","mstr_symbols","I117";
;
HDL_POWER"GND"
BODY_TYPE"PLUMBING"
ROOM"VDDQ_KLM_PWR_VR"
VOLTAGE"0"
SIZE"1B"
CDS_LIB"mstr_symbols";
"A\NAC"7;
%"CAP"
"1","(3000,2375)","0","mstr_discrete","I118";
;
CDS_SEC"1"
CDS_LOCATION"CT49"
POP"NOPOP"
LOCATION"CT49"
PART_NUMBER"A36096-046"
MATERIAL"X7R"
TOLERANCE"10%"
VOLTAGE"50V"
VALUE"1000PF"
PACK_TYPE"0402LF"
SEC_TYPE"0402LF"
SEC"1"
ROOM"VDDQ_KLM_PWR_VR"
CDS_LIB"mstr_discrete";
"A"
$PN"1"24;
"B"
$PN"2"7;
%"GND"
"1","(2900,-1050)","0","mstr_symbols","I120";
;
HDL_POWER"GND"
BODY_TYPE"PLUMBING"
CDS_LIB"mstr_symbols"
ROOM"PVCCIN_CPU0_PWR_VR"
BOM_COST"PROC_VRD_VCCIN_CPU0"
VOLTAGE"0"
SIZE"1B";
"A\NAC"8;
%"CAP"
"1","(2900,-75)","0","mstr_discrete","I121";
;
CDS_SEC"1"
CDS_LOCATION"CT54"
POP"NOPOP"
LOCATION"CT54"
VOLTAGE"50V"
TOLERANCE"10%"
MATERIAL"X7R"
PACK_TYPE"0402LF"
PART_NUMBER"A36096-046"
BOM_SS"NOPOP"
VALUE"1000PF"
SEC_TYPE"0402LF"
SEC"1"
ROOM"VDDQ_KLM_PWR_VR"
CDS_LIB"mstr_discrete";
"A"
$PN"1"28;
"B"
$PN"2"9;
%"GND"
"1","(2900,-275)","0","mstr_symbols","I122";
;
HDL_POWER"GND"
BODY_TYPE"PLUMBING"
SIZE"1B"
VOLTAGE"0"
ROOM"VDDQ_KLM_PWR_VR"
CDS_LIB"mstr_symbols";
"A\NAC"9;
%"CAP"
"1","(-800,-425)","2","mstr_discrete","I128";
;
PART_NUMBER"A36096-104"
VALUE"0.220UF"
PACK_TYPE"0402"
MATERIAL"X7R"
TOLERANCE"10%"
VOLTAGE"16V"
LOCATION"C7G38"
BOM_SS"NOPOP"
CDS_LIB"mstr_discrete"
SEC_TYPE"0402"
SPOF"TRUE"
SEC"1"
CDS_LOCATION"C7G38"
ROOM"VDDQ_ABC_PWR_VR"
CDS_SEC"1";
"A"
$PN"1"45;
"B"
$PN"2"37;
%"CAP"
"1","(2900,1850)","0","mstr_discrete","I135";
;
CDS_SEC"1"
CDS_LOCATION"CT50"
MATERIAL"X7R"
LOCATION"CT50"
TOLERANCE"10%"
VOLTAGE"50V"
VALUE"1000PF"
POP"NOPOP"
PACK_TYPE"0402LF"
PART_NUMBER"A36096-046"
SEC_TYPE"0402LF"
SEC"1"
ROOM"VDDQ_KLM_PWR_VR"
CDS_LIB"mstr_discrete";
"A"
$PN"1"26;
"B"
$PN"2"25;
%"CAP"
"1","(2900,-525)","0","mstr_discrete","I136";
;
CDS_SEC"1"
CDS_LOCATION"CT53"
TOLERANCE"10%"
LOCATION"CT53"
PART_NUMBER"A36096-046"
POP"NOPOP"
MATERIAL"X7R"
PACK_TYPE"0402LF"
BOM_SS"NOPOP"
VALUE"1000PF"
VOLTAGE"50V"
CDS_LIB"mstr_discrete"
ROOM"VDDQ_KLM_PWR_VR"
SEC"1"
SEC_TYPE"0402LF";
"A"
$PN"1"36;
"B"
$PN"2"35;
%"RES"
"1","(125,2075)","0","mstr_discrete","I139";
;
CDS_SEC"1"
CDS_LOCATION"RT33"
LOCATION"RT33"
WATTAGE"1/10W"
PART_NUMBER"G22178-002"
TOLERANCE"5.0%"
MATERIAL"CHIP"
PACK_TYPE"0603"
VALUE"0"
SEC_TYPE"0603"
SEC"1"
BOM_COST"NT_GBE_BASE"
ROOM"NIC_SPRV"
CDS_LIB"mstr_discrete";
"B"
$PN"2"33;
"A"
$PN"1"42;
%"RES"
"1","(100,-275)","0","mstr_discrete","I140";
;
CDS_SEC"1"
CDS_LOCATION"RT36"
PART_NUMBER"G22178-002"
LOCATION"RT36"
PACK_TYPE"0603"
VALUE"0"
TOLERANCE"5.0%"
WATTAGE"1/10W"
MATERIAL"CHIP"
BOM_SS"NOPOP"
SEC_TYPE"0603"
SEC"1"
ROOM"NIC_SPRV"
BOM_COST"NT_GBE_BASE"
CDS_LIB"mstr_discrete";
"B"
$PN"2"38;
"A"
$PN"1"45;
%"RES"
"1","(-575,3100)","0","mstr_discrete","I145";
;
TOLERANCE"5%"
VALUE"0.0"
PACK_TYPE"0402"
MATERIAL"CHIP"
PART_NUMBER"G21497-005"
LOCATION"R3U6"
WATTAGE"1/16W"
BOM_COST"PROC_SIDEBAND"
CDS_LIB"mstr_discrete"
SEC_TYPE"0402"
SEC"1"
ROOM"CPU0"
CDS_SEC"1"
CDS_LOCATION"R3U6";
"B"
$PN"2"19;
"A"
$PN"1"44;
%"RES"
"1","(-600,725)","0","mstr_discrete","I146";
;
VALUE"0.0"
TOLERANCE"5%"
LOCATION"R3U9"
PACK_TYPE"0402"
BOM_SS"NOPOP"
PART_NUMBER"G21497-005"
MATERIAL"CHIP"
WATTAGE"1/16W"
CDS_LOCATION"R3U9"
BOM_COST"PROC_SIDEBAND"
CDS_LIB"mstr_discrete"
SEC_TYPE"0402"
SEC"1"
ROOM"CPU0"
CDS_SEC"1";
"B"
$PN"2"20;
"A"
$PN"1"46;
%"SC1U10V2KX-4-GP"
"1","(-250,2525)","0","w_hdl","I149";
;
CDS_SEC"1"
CDS_LOCATION"C7G35"
RATED"10V"
PACK_SIZE"0402"
TOLERANCE"10%"
ATTRIBUTE"1UF"
VALUE"SC1U10V2KX-4-GP"
LOCATION"C7G35"
PACK_TYPE"SMD-BCG6"
SEC"1"
SEC_TYPE"SMD-BCG6"
PART_NUMBER"78.10523.8FL"
CDS_LIB"w_hdl"
CDS_LMAN_SYM_OUTLINE"-50,25,50,-25";
"2"
$PN"2"11;
"1"
$PN"1"19;
%"SC1U10V2KX-4-GP"
"1","(-325,175)","0","w_hdl","I150";
;
CDS_SEC"1"
CDS_LOCATION"C7G42"
VALUE"SC1U10V2KX-4-GP"
TOLERANCE"10%"
PACK_SIZE"0402"
RATED"10V"
ATTRIBUTE"1UF"
LOCATION"C7G42"
BOM_SS"NOPOP"
CDS_LMAN_SYM_OUTLINE"-50,25,50,-25"
CDS_LIB"w_hdl"
PART_NUMBER"78.10523.8FL"
SEC_TYPE"SMD-BCG6"
SEC"1"
PACK_TYPE"SMD-BCG6";
"2"
$PN"2"17;
"1"
$PN"1"20;
%"1R3F-GP"
"1","(2900,1500)","0","w_hdl","I151";
;
CDS_SEC"1"
CDS_LOCATION"RT34"
TOLERANCE"1%"
PACK_SIZE"0603"
LOCATION"RT34"
RATED"1/10W"
VALUE"1R3F-GP"
ATTRIBUTE"1 OHM"
POP"NOPOP"
CDS_LMAN_SYM_OUTLINE"-50,75,50,-75"
CDS_LIB"w_hdl"
PART_NUMBER"64.1R005.55L"
SEC_TYPE"RCL_GP"
SEC"1"
PACK_TYPE"RCL_GP";
"2"
$PN"2"6;
"1"
$PN"1"25;
%"1R3F-GP"
"1","(2900,-850)","0","w_hdl","I152";
;
CDS_SEC"1"
CDS_LOCATION"RT35"
PACK_SIZE"0603"
TOLERANCE"1%"
LOCATION"RT35"
RATED"1/10W"
ATTRIBUTE"1 OHM"
VALUE"1R3F-GP"
POP"NOPOP"
BOM_SS"NOPOP"
PACK_TYPE"RCL_GP"
SEC"1"
SEC_TYPE"RCL_GP"
PART_NUMBER"64.1R005.55L"
CDS_LIB"w_hdl"
CDS_LMAN_SYM_OUTLINE"-50,75,50,-75";
"2"
$PN"2"8;
"1"
$PN"1"35;
%"IND-120NH-30-GP"
"1","(3900,2025)","1","w_hdl","I153";
;
CDS_SEC"1"
CDS_LOCATION"L7G1"
DS_VALUE"90NH"
NEW_PACK_SIZE"DCR=0.17MOHM"
LOCATION"L7G1"
SS_ISAT"94A@25C"
BOM_DS"068.9002N.1021"
NEW_RATED"DS_ISAT=134A@25C"
NEW_TYPE"IRMS=66A@DELTA_T<40C"
SS_VALUE"120NH"
BOM_SS"068.1202N.M001"
TYPE"IRMS=66A@DELTA_T<40C"
PACK_SIZE"DCR=0.17MOHM"
RATED"ISAT=94A@25C"
ATTRIBUTE"120NH"
VALUE"IND-120NH-30-GP"
PACK_TYPE"DISCRET-GB2"
SEC"1"
SEC_TYPE"DISCRET-GB2"
CDS_LMAN_SYM_OUTLINE"-75,100,75,-100"
CDS_LIB"w_hdl"
PART_NUMBER"068.1202N.M001";
"F"
$PN"2"1;
"S"
$PN"1"26;
%"IND-120NH-30-GP"
"1","(3950,-350)","1","w_hdl","I155";
;
CDS_SEC"1"
CDS_LOCATION"L7G2"
LOCATION"L7G2"
NEW_PACK_SIZE"DCR=0.17MOHM"
NEW_RATED"DS_ISAT=134A@25C"
DS_VALUE"90NH"
BOM_DS"068.9002N.1021"
BOM_SS"NOPOP"
NEW_TYPE"IRMS=66A@DELTA_T<40C"
PART_NUMBER"068.1202N.M001"
CDS_LIB"w_hdl"
CDS_LMAN_SYM_OUTLINE"-75,100,75,-100"
SEC_TYPE"DISCRET-GB2"
SEC"1"
PACK_TYPE"DISCRET-GB2"
VALUE"IND-120NH-30-GP"
ATTRIBUTE"120NH"
RATED"ISAT=94A@25C"
PACK_SIZE"DCR=0.17MOHM"
TYPE"IRMS=66A@DELTA_T<40C";
"F"
$PN"2"12;
"S"
$PN"1"36;
%"GND"
"1","(2450,1625)","0","mstr_symbols","I19";
;
HDL_POWER"GND"
BODY_TYPE"PLUMBING"
ROOM"VDDQ_ABC_PWR_VR"
BOM_COST"PROC_VRD_VCCIN_CPU0"
SIZE"1B"
CDS_LIB"mstr_symbols"
VOLTAGE"0";
"A\NAC"10;
%"GND"
"1","(-2050,2050)","0","mstr_symbols","I35";
;
HDL_POWER"GND"
BODY_TYPE"PLUMBING"
CDS_LIB"mstr_symbols"
VOLTAGE"0"
BOM_COST"PROC_VRD_VCCIN_CPU0"
ROOM"VDDQ_ABC_PWR_VR"
SIZE"1B";
"A\NAC"11;
%"CAP"
"1","(-675,1925)","2","mstr_discrete","I44";
;
CDS_SEC"1"
TOLERANCE"10%"
VOLTAGE"16V"
MATERIAL"X7R"
VALUE"0.220UF"
PACK_TYPE"0402"
PART_NUMBER"A36096-104"
LOCATION"C7G31"
CDS_LIB"mstr_discrete"
SEC_TYPE"0402"
SPOF"TRUE"
SEC"1"
CDS_LOCATION"C7G31"
ROOM"VDDQ_ABC_PWR_VR";
"A"
$PN"1"42;
"B"
$PN"2"34;
%"CAP"
"1","(-2050,2525)","0","mstr_discrete","I45";
;
CDS_SEC"1"
PACK_TYPE"0805"
MATERIAL"X6S"
VOLTAGE"16V"
TOLERANCE"10%"
PART_NUMBER"C95333-007"
LOCATION"C3U2"
VALUE"10UF"
SEC_TYPE"0805"
SEC"1"
ROOM"VDDQ_ABC_PWR_VR"
CDS_LOCATION"C3U2"
CDS_LIB"mstr_discrete";
"A"
$PN"1"18;
"B"
$PN"2"11;
%"CAP"
"1","(-1775,2525)","0","mstr_discrete","I46";
;
CDS_SEC"1"
PACK_TYPE"0805"
MATERIAL"X6S"
TOLERANCE"10%"
VOLTAGE"16V"
VALUE"10UF"
LOCATION"C3U3"
PART_NUMBER"C95333-007"
CDS_LOCATION"C3U3"
SEC"1"
SEC_TYPE"0805"
ROOM"VDDQ_ABC_PWR_VR"
CDS_LIB"mstr_discrete";
"A"
$PN"1"18;
"B"
$PN"2"11;
%"CAP"
"1","(-1525,2525)","0","mstr_discrete","I47";
;
CDS_SEC"1"
PACK_TYPE"0805"
VOLTAGE"16V"
MATERIAL"X6S"
TOLERANCE"10%"
PART_NUMBER"C95333-007"
LOCATION"C3U4"
VALUE"10UF"
SEC_TYPE"0805"
ROOM"VDDQ_ABC_PWR_VR"
CDS_LOCATION"C3U4"
SEC"1"
CDS_LIB"mstr_discrete";
"A"
$PN"1"18;
"B"
$PN"2"11;
%"CAP"
"1","(-1275,2525)","0","mstr_discrete","I48";
;
CDS_SEC"1"
VOLTAGE"16V"
MATERIAL"X6S"
TOLERANCE"10%"
PACK_TYPE"0402"
VALUE"1.0UF"
LOCATION"C7G37"
PART_NUMBER"D97712-011"
CDS_LIB"mstr_discrete"
SEC_TYPE"0402"
SEC"1"
CDS_LOCATION"C7G37"
ROOM"VDDQ_ABC_PWR_VR";
"A"
$PN"1"18;
"B"
$PN"2"11;
%"CAP"
"1","(-725,2525)","0","mstr_discrete","I50";
;
CDS_SEC"1"
TOLERANCE"10%"
MATERIAL"X6S"
VOLTAGE"16V"
PACK_TYPE"0402"
VALUE"1.0UF"
LOCATION"C7G33"
PART_NUMBER"D97712-011"
ROOM"VDDQ_ABC_PWR_VR"
CDS_LOCATION"C7G33"
SEC"1"
SEC_TYPE"0402"
CDS_LIB"mstr_discrete";
"A"
$PN"1"44;
"B"
$PN"2"11;
%"CAP_A"
"1","(-1000,2525)","0","dev_discrete","I51";
;
PACK_TYPE"0402V"
VOLTAGE"16V"
TOLERANCE"10%"
MATERIAL"X7R"
PART_NUMBER"A36096-030"
VALUE"0.1UF"
LOCATION"C7G29"
CDS_LIB"dev_discrete"
SEC"1"
SEC_TYPE"0402V"
CDS_SEC"1"
CDS_LOCATION"C7G29"
ROOM"VDDQ_ABC_PWR_VR";
"B"
$PN"2"11;
"A"
$PN"1"18;
%"CAP"
"1","(100,2550)","0","mstr_discrete","I54";
;
CDS_SEC"1"
MATERIAL"X7R"
TOLERANCE"10%"
PART_NUMBER"A36096-155"
PACK_TYPE"0402"
VOLTAGE"16V"
LOCATION"C7G34"
VALUE"0.22UF"
ROOM"VDDQ_ABC_PWR_VR"
CDS_LOCATION"C7G34"
SEC"1"
SEC_TYPE"0402"
CDS_LIB"mstr_discrete";
"A"
$PN"1"19;
"B"
$PN"2"11;
%"CAP"
"1","(4350,1850)","0","mstr_discrete","I6";
;
CDS_SEC"1"
MATERIAL"X6S"
TOLERANCE"20%"
VALUE"22UF"
LOCATION"C6G3"
PACK_TYPE"0805LF"
VOLTAGE"4V"
PART_NUMBER"C95333-002"
GROUP"PWR_MLCC_CAP"
CDS_LIB"mstr_discrete"
CDS_LOCATION"C6G3"
ROOM"VDDQ_ABC_PWR_VR"
BOM_COST"PROC_VRD_VCCIN_CPU0"
SEC"1"
SEC_TYPE"0805LF";
"A"
$PN"1"1;
"B"
$PN"2"14;
%"PVDDQ_ABC"
"1","(4400,-275)","0","mstr_symbols","I64";
;
HDL_POWER"PVDDQ_ABC"
BODY_TYPE"PLUMBING"
CDS_LIB"mstr_symbols"
VOLTAGE"1.2V"
ROOM"VDDQ_ABC_PWR_VR"
BOM_COST"PROC_SOCKET ";
"G\NAC"12;
%"CAP"
"1","(4400,-550)","0","mstr_discrete","I68";
;
CDS_SEC"1"
VOLTAGE"4V"
MATERIAL"X6S"
TOLERANCE"20%"
VALUE"22UF"
LOCATION"C7G27"
BOM_SS"NOPOP"
GROUP"PWR_MLCC_CAP"
PART_NUMBER"C95333-002"
PACK_TYPE"0805LF"
CDS_LIB"mstr_discrete"
CDS_LOCATION"C7G27"
ROOM"VDDQ_ABC_PWR_VR"
SEC"1"
SEC_TYPE"0805LF"
BOM_COST"PROC_VRD_VCCIN_CPU0";
"A"
$PN"1"12;
"B"
$PN"2"13;
%"GND"
"1","(4400,-800)","0","mstr_symbols","I69";
;
HDL_POWER"GND"
BODY_TYPE"PLUMBING"
ROOM"VDDQ_ABC_PWR_VR"
BOM_COST"PROC_VRD_VCCIN_CPU0"
VOLTAGE"0"
CDS_LIB"mstr_symbols"
SIZE"1B";
"A\NAC"13;
%"GND"
"1","(4350,1625)","0","mstr_symbols","I7";
;
HDL_POWER"GND"
BODY_TYPE"PLUMBING"
ROOM"VDDQ_ABC_PWR_VR"
CDS_LIB"mstr_symbols"
SIZE"1B"
VOLTAGE"0"
BOM_COST"PROC_VRD_VCCIN_CPU0";
"A\NAC"14;
%"GND"
"1","(2450,-825)","0","mstr_symbols","I70";
;
HDL_POWER"GND"
BODY_TYPE"PLUMBING"
ROOM":VCCIN_CPU0_PWR_VR"
BOM_COST"PROC_VRD_VCCIN_CPU0"
VOLTAGE"0"
SIZE"1B"
CDS_LIB"mstr_symbols";
"A\NAC"15;
%"CAP"
"1","(50,200)","0","mstr_discrete","I72";
;
CDS_SEC"1"
PACK_TYPE"0402"
MATERIAL"X7R"
TOLERANCE"10%"
VOLTAGE"16V"
LOCATION"C7G41"
PART_NUMBER"A36096-155"
VALUE"0.22UF"
BOM_SS"NOPOP"
ROOM"VDDQ_ABC_PWR_VR"
SEC_TYPE"0402"
SEC"1"
CDS_LOCATION"C7G41"
CDS_LIB"mstr_discrete";
"A"
$PN"1"20;
"B"
$PN"2"17;
%"CAP"
"1","(-825,175)","0","mstr_discrete","I77";
;
CDS_SEC"1"
BOM_SS"NOPOP"
PACK_TYPE"0402"
LOCATION"C7G40"
TOLERANCE"10%"
VALUE"1.0UF"
VOLTAGE"16V"
MATERIAL"X6S"
PART_NUMBER"D97712-011"
CDS_LIB"mstr_discrete"
CDS_LOCATION"C7G40"
ROOM"VDDQ_ABC_PWR_VR"
SEC"1"
SEC_TYPE"0402";
"A"
$PN"1"46;
"B"
$PN"2"17;
%"CAP_A"
"1","(-1075,175)","0","dev_discrete","I78";
;
PACK_TYPE"0402V"
PART_NUMBER"A36096-030"
MATERIAL"X7R"
TOLERANCE"10%"
VOLTAGE"16V"
VALUE"0.1UF"
LOCATION"C7G36"
SEC"1"
SEC_TYPE"0402V"
CDS_SEC"1"
ROOM"VDDQ_ABC_PWR_VR"
CDS_LIB"dev_discrete"
CDS_LOCATION"C7G36";
"B"
$PN"2"17;
"A"
$PN"1"16;
%"CAP"
"1","(-1325,175)","0","mstr_discrete","I79";
;
CDS_SEC"1"
PACK_TYPE"0402"
VALUE"1.0UF"
VOLTAGE"16V"
MATERIAL"X6S"
TOLERANCE"10%"
LOCATION"C7G30"
PART_NUMBER"D97712-011"
CDS_LIB"mstr_discrete"
CDS_LOCATION"C7G30"
SEC_TYPE"0402"
SEC"1"
ROOM"VDDQ_ABC_PWR_VR";
"A"
$PN"1"16;
"B"
$PN"2"17;
%"CAP"
"1","(-1550,175)","0","mstr_discrete","I80";
;
CDS_SEC"1"
PACK_TYPE"0805"
VOLTAGE"16V"
TOLERANCE"10%"
MATERIAL"X6S"
VALUE"10UF"
LOCATION"C3U9"
PART_NUMBER"C95333-007"
CDS_LOCATION"C3U9"
CDS_LIB"mstr_discrete"
ROOM"VDDQ_ABC_PWR_VR"
SEC"1"
SEC_TYPE"0805";
"A"
$PN"1"16;
"B"
$PN"2"17;
%"CAP"
"1","(-1800,175)","0","mstr_discrete","I81";
;
CDS_SEC"1"
PACK_TYPE"0805"
TOLERANCE"10%"
MATERIAL"X6S"
VALUE"10UF"
VOLTAGE"16V"
LOCATION"C3U7"
PART_NUMBER"C95333-007"
ROOM"VDDQ_ABC_PWR_VR"
SEC"1"
SEC_TYPE"0805"
CDS_LOCATION"C3U7"
CDS_LIB"mstr_discrete";
"A"
$PN"1"16;
"B"
$PN"2"17;
%"VCC_CORE"
"1","(-2050,475)","0","mstr_symbols","I83";
;
HDL_POWER"VR_FET_SW_P12V_STBY_PVDDQ_ABC"
CDS_LIB"mstr_symbols";
"A"16;
%"CAP"
"1","(-2050,175)","0","mstr_discrete","I84";
;
CDS_SEC"1"
PACK_TYPE"0805"
MATERIAL"X6S"
VALUE"10UF"
TOLERANCE"10%"
VOLTAGE"16V"
LOCATION"C3U6"
PART_NUMBER"C95333-007"
CDS_LIB"mstr_discrete"
CDS_LOCATION"C3U6"
ROOM"VDDQ_ABC_PWR_VR"
SEC_TYPE"0805"
SEC"1";
"A"
$PN"1"16;
"B"
$PN"2"17;
%"GND"
"1","(-2050,-175)","0","mstr_symbols","I85";
;
ROOM"VDDQ_ABC_PWR_VR"
BOM_COST"PROC_VRD_VCCIN_CPU0"
VOLTAGE"0"
CDS_LIB"mstr_symbols"
SIZE"1B"
BODY_TYPE"PLUMBING"
HDL_POWER"GND";
"A\NAC"17;
%"VCC_CORE"
"1","(-1625,2900)","0","mstr_symbols","I86";
;
HDL_POWER"VR_FET_SW_P12V_STBY_PVDDQ_ABC"
CDS_LIB"mstr_symbols";
"A"18;
%"P5V_STBY"
"1","(350,3250)","0","mstr_symbols","I87";
;
HDL_POWER"P5V_STBY"
BODY_TYPE"PLUMBING"
VOLTAGE"5.0V"
CDS_LIB"mstr_symbols"
SIZE"1B";
"G\NAC"19;
%"P5V_STBY"
"1","(500,900)","0","mstr_symbols","I88";
;
HDL_POWER"P5V_STBY"
BODY_TYPE"PLUMBING"
VOLTAGE"5.0V"
SIZE"1B"
CDS_LIB"mstr_symbols";
"G\NAC"20;
END.
